# SCM (Grand Teton) — schematic netlist excerpt (pin names and nets, part order shuffled) for the footprints in the layout excerpt that follows; sources: Cadence DE-HDL packaged netlist, KiCad conversion of 12092022_DA0F0TMDCD0_F0T_Management_Board_D_brd_V3_OCP.brd

C299  Q_CAP  0.1UF 25V 10% X7R  pkg 0402  page 15 : A = P3V3_SENSOR ; B = GND
C91  Q_CAP  0.1UF 25V 10% X7R  pkg 0402  page 16 : A = P1V2_AUX ; B = GND

(kicad_pcb
	(version 20260206)
	(generator "pcbnew")
	(generator_version "10.0")
	(general
		(thickness 1.6)
		(legacy_teardrops no)
	)
	(paper "A4")
	(title_block
		(title "12092022_DA0F0TMDCD0_F0T_Management_Board_D_brd_V3_OCP.brd")
		(comment 1 "Grand Teton / footprints 1082-1083 of 1440")
	)
	(layers
		(0 "F.Cu" signal "TOP")
		(4 "In1.Cu" signal "GND")
		(6 "In2.Cu" signal "IN1")
		(8 "In3.Cu" signal "GND1")
		(10 "In4.Cu" signal "IN2")
		(12 "In5.Cu" signal "VCC")
		(14 "In6.Cu" signal "VCC1")
		(16 "In7.Cu" signal "IN3")
		(18 "In8.Cu" signal "GND2")
		(20 "In9.Cu" signal "IN4")
		(22 "In10.Cu" signal "GND3")
		(2 "B.Cu" signal "BOTTOM")
		(9 "F.Adhes" user "F.Adhesive")
		(11 "B.Adhes" user "B.Adhesive")
		(13 "F.Paste" user "Package Geometry/Pastemask Top")
		(15 "B.Paste" user "Package Geometry/Pastemask Bottom")
		(5 "F.SilkS" user "Ref Des/Silkscreen Top")
		(7 "B.SilkS" user "Ref Des/Silkscreen Bottom")
		(1 "F.Mask" user "Board Geometry/Soldermask Top")
		(3 "B.Mask" user "Board Geometry/Soldermask Bottom")
		(17 "Dwgs.User" user "User.Drawings")
		(19 "Cmts.User" user "User.Comments")
		(21 "Eco1.User" user "User.Eco1")
		(23 "Eco2.User" user "User.Eco2")
		(25 "Edge.Cuts" user "Board Geometry/Outline")
		(27 "Margin" user)
		(31 "F.CrtYd" user "Package Geometry/Place Bound Top")
		(29 "B.CrtYd" user "Package Geometry/Place Bound Bottom")
		(35 "F.Fab" user "Ref Des/Assembly Top")
		(33 "B.Fab" user "Ref Des/Assembly Bottom")
	)
	(footprint ""
		(layer "B.Cu")
		(at 52.27574 -69.397372 -90)
		(property "Reference" "C299"
			(at 0 0 90)
			(layer "B.SilkS")
			(hide yes)
			(effects
				(font
					(size 1.27 1.27)
				)
				(justify mirror)
			)
		)
		(property "Value" ""
			(at 0 0 90)
			(layer "B.Fab")
			(effects
				(font
					(size 1.27 1.27)
				)
				(justify mirror)
			)
		)
		(duplicate_pad_numbers_are_jumpers no)
		(fp_line
			(start -0.7874 0.4064)
			(end 0.7874 0.4064)
			(stroke
				(width 0.1524)
				(type default)
			)
			(layer "B.SilkS")
		)
		(fp_line
			(start 0.7874 0.4064)
			(end 0.7874 -0.4064)
			(stroke
				(width 0.1524)
				(type default)
			)
			(layer "B.SilkS")
		)
		(fp_line
			(start -0.7874 -0.4064)
			(end -0.7874 0.4064)
			(stroke
				(width 0.1524)
				(type default)
			)
			(layer "B.SilkS")
		)
		(fp_line
			(start 0.7874 -0.4064)
			(end -0.7874 -0.4064)
			(stroke
				(width 0.1524)
				(type default)
			)
			(layer "B.SilkS")
		)
		(fp_line
			(start -0.67945 0.3048)
			(end -0.120396 0.3048)
			(stroke
				(width 0.1)
				(type default)
			)
			(layer "B.Fab")
		)
		(fp_line
			(start -0.120396 0.3048)
			(end -0.120396 0.2794)
			(stroke
				(width 0.1)
				(type default)
			)
			(layer "B.Fab")
		)
		(fp_line
			(start 0.12065 0.3048)
			(end 0.67945 0.3048)
			(stroke
				(width 0.1)
				(type default)
			)
			(layer "B.Fab")
		)
		(fp_line
			(start 0.67945 0.3048)
			(end 0.67945 -0.305054)
			(stroke
				(width 0.1)
				(type default)
			)
			(layer "B.Fab")
		)
		(fp_line
			(start -0.120396 0.2794)
			(end 0.12065 0.2794)
			(stroke
				(width 0.1)
				(type default)
			)
			(layer "B.Fab")
		)
		(fp_line
			(start 0.12065 0.2794)
			(end 0.12065 0.3048)
			(stroke
				(width 0.1)
				(type default)
			)
			(layer "B.Fab")
		)
		(fp_line
			(start -0.12065 -0.2794)
			(end -0.12065 -0.3048)
			(stroke
				(width 0.1)
				(type default)
			)
			(layer "B.Fab")
		)
		(fp_line
			(start 0.12065 -0.2794)
			(end -0.12065 -0.2794)
			(stroke
				(width 0.1)
				(type default)
			)
			(layer "B.Fab")
		)
		(fp_line
			(start -0.67945 -0.3048)
			(end -0.67945 0.3048)
			(stroke
				(width 0.1)
				(type default)
			)
			(layer "B.Fab")
		)
		(fp_line
			(start -0.12065 -0.3048)
			(end -0.67945 -0.3048)
			(stroke
				(width 0.1)
				(type default)
			)
			(layer "B.Fab")
		)
		(fp_line
			(start 0.12065 -0.305054)
			(end 0.12065 -0.2794)
			(stroke
				(width 0.1)
				(type default)
			)
			(layer "B.Fab")
		)
		(fp_line
			(start 0.67945 -0.305054)
			(end 0.12065 -0.305054)
			(stroke
				(width 0.1)
				(type default)
			)
			(layer "B.Fab")
		)
		(pad "1" smd circle
			(at 0.40005 0 90)
			(size 0 0)
			(layers "B.Cu" "B.Mask" "B.Paste")
			(net "P3V3_SENSOR")
		)
		(pad "2" smd circle
			(at -0.40005 0 90)
			(size 0 0)
			(layers "B.Cu" "B.Mask" "B.Paste")
			(net "GND")
		)
	)
	(footprint ""
		(layer "B.Cu")
		(at 52.701444 -47.617126 -90)
		(property "Reference" "C91"
			(at 0 0 90)
			(layer "B.SilkS")
			(hide yes)
			(effects
				(font
					(size 1.27 1.27)
				)
				(justify mirror)
			)
		)
		(property "Value" ""
			(at 0 0 90)
			(layer "B.Fab")
			(effects
				(font
					(size 1.27 1.27)
				)
				(justify mirror)
			)
		)
		(duplicate_pad_numbers_are_jumpers no)
		(fp_line
			(start -0.7874 0.4064)
			(end 0.7874 0.4064)
			(stroke
				(width 0.1524)
				(type default)
			)
			(layer "B.SilkS")
		)
		(fp_line
			(start 0.7874 0.4064)
			(end 0.7874 -0.4064)
			(stroke
				(width 0.1524)
				(type default)
			)
			(layer "B.SilkS")
		)
		(fp_line
			(start -0.7874 -0.4064)
			(end -0.7874 0.4064)
			(stroke
				(width 0.1524)
				(type default)
			)
			(layer "B.SilkS")
		)
		(fp_line
			(start 0.7874 -0.4064)
			(end -0.7874 -0.4064)
			(stroke
				(width 0.1524)
				(type default)
			)
			(layer "B.SilkS")
		)
		(fp_line
			(start -0.67945 0.3048)
			(end -0.120396 0.3048)
			(stroke
				(width 0.1)
				(type default)
			)
			(layer "B.Fab")
		)
		(fp_line
			(start -0.120396 0.3048)
			(end -0.120396 0.2794)
			(stroke
				(width 0.1)
				(type default)
			)
			(layer "B.Fab")
		)
		(fp_line
			(start 0.12065 0.3048)
			(end 0.67945 0.3048)
			(stroke
				(width 0.1)
				(type default)
			)
			(layer "B.Fab")
		)
		(fp_line
			(start 0.67945 0.3048)
			(end 0.67945 -0.305054)
			(stroke
				(width 0.1)
				(type default)
			)
			(layer "B.Fab")
		)
		(fp_line
			(start -0.120396 0.2794)
			(end 0.12065 0.2794)
			(stroke
				(width 0.1)
				(type default)
			)
			(layer "B.Fab")
		)
		(fp_line
			(start 0.12065 0.2794)
			(end 0.12065 0.3048)
			(stroke
				(width 0.1)
				(type default)
			)
			(layer "B.Fab")
		)
		(fp_line
			(start -0.12065 -0.2794)
			(end -0.12065 -0.3048)
			(stroke
				(width 0.1)
				(type default)
			)
			(layer "B.Fab")
		)
		(fp_line
			(start 0.12065 -0.2794)
			(end -0.12065 -0.2794)
			(stroke
				(width 0.1)
				(type default)
			)
			(layer "B.Fab")
		)
		(fp_line
			(start -0.67945 -0.3048)
			(end -0.67945 0.3048)
			(stroke
				(width 0.1)
				(type default)
			)
			(layer "B.Fab")
		)
		(fp_line
			(start -0.12065 -0.3048)
			(end -0.67945 -0.3048)
			(stroke
				(width 0.1)
				(type default)
			)
			(layer "B.Fab")
		)
		(fp_line
			(start 0.12065 -0.305054)
			(end 0.12065 -0.2794)
			(stroke
				(width 0.1)
				(type default)
			)
			(layer "B.Fab")
		)
		(fp_line
			(start 0.67945 -0.305054)
			(end 0.12065 -0.305054)
			(stroke
				(width 0.1)
				(type default)
			)
			(layer "B.Fab")
		)
		(pad "1" smd circle
			(at 0.40005 0 90)
			(size 0 0)
			(layers "B.Cu" "B.Mask" "B.Paste")
			(net "P1V2_AUX")
		)
		(pad "2" smd circle
			(at -0.40005 0 90)
			(size 0 0)
			(layers "B.Cu" "B.Mask" "B.Paste")
			(net "GND")
		)
	)
)
